(kicad_pcb
	(version 20260206)
	(generator "pcbnew")
	(generator_version "10.0")
	(general
		(thickness 1.6)
		(legacy_teardrops no)
	)
	(paper "A4")
	(title_block
		(title "04192023_DAF0TMB3IC0_F0TG_MB_C_brd_V02_OCP.brd")
		(comment 1 "Grand Teton / footprints 1357-1361 of 8354")
	)
	(layers
		(0 "F.Cu" signal "TOP")
		(4 "In1.Cu" signal "GND")
		(6 "In2.Cu" signal "IN1")
		(8 "In3.Cu" signal "GND1")
		(10 "In4.Cu" signal "IN2")
		(12 "In5.Cu" signal "GND2")
		(14 "In6.Cu" signal "IN3")
		(16 "In7.Cu" signal "GND3")
		(18 "In8.Cu" signal "VCC")
		(20 "In9.Cu" signal "VCC1")
		(22 "In10.Cu" signal "GND4")
		(24 "In11.Cu" signal "IN4")
		(26 "In12.Cu" signal "GND5")
		(28 "In13.Cu" signal "IN5")
		(30 "In14.Cu" signal "GND6")
		(32 "In15.Cu" signal "IN6")
		(34 "In16.Cu" signal "GND7")
		(2 "B.Cu" signal "BOTTOM")
		(9 "F.Adhes" user "F.Adhesive")
		(11 "B.Adhes" user "B.Adhesive")
		(13 "F.Paste" user "Package Geometry/Pastemask Top")
		(15 "B.Paste" user "Package Geometry/Pastemask Bottom")
		(5 "F.SilkS" user "Ref Des/Silkscreen Top")
		(7 "B.SilkS" user "Ref Des/Silkscreen Bottom")
		(1 "F.Mask" user "Board Geometry/Soldermask Top")
		(3 "B.Mask" user "Board Geometry/Soldermask Bottom")
		(17 "Dwgs.User" user "User.Drawings")
		(19 "Cmts.User" user "User.Comments")
		(21 "Eco1.User" user "User.Eco1")
		(23 "Eco2.User" user "User.Eco2")
		(25 "Edge.Cuts" user "Board Geometry/Outline")
		(27 "Margin" user)
		(31 "F.CrtYd" user "Package Geometry/Place Bound Top")
		(29 "B.CrtYd" user "Package Geometry/Place Bound Bottom")
		(35 "F.Fab" user "Ref Des/Assembly Top")
		(33 "B.Fab" user "Ref Des/Assembly Bottom")
	)
	(footprint ""
		(layer "F.Cu")
		(at 28.600654 -346.721176)
		(property "Reference" "PU53"
			(at -3.073654 -7.709154 0)
			(unlocked yes)
			(layer "F.SilkS")
			(effects
				(font
					(size 0.7874 0.5842)
					(thickness 0.1524)
				)
				(justify left)
			)
		)
		(property "Value" ""
			(at 0 0 0)
			(layer "F.Fab")
			(effects
				(font
					(size 1.27 1.27)
				)
			)
		)
		(duplicate_pad_numbers_are_jumpers no)
		(fp_line
			(start -2.500122 -2.999994)
			(end -2.24409 -2.999994)
			(stroke
				(width 0.1524)
				(type default)
			)
			(layer "F.SilkS")
		)
		(fp_line
			(start -2.500122 -2.529078)
			(end -2.500122 -2.999994)
			(stroke
				(width 0.1524)
				(type default)
			)
			(layer "F.SilkS")
		)
		(fp_line
			(start -2.500122 0.6604)
			(end -2.500122 0.229108)
			(stroke
				(width 0.1524)
				(type default)
			)
			(layer "F.SilkS")
		)
		(fp_line
			(start -2.500122 2.999994)
			(end -2.500122 2.339594)
			(stroke
				(width 0.1524)
				(type default)
			)
			(layer "F.SilkS")
		)
		(fp_line
			(start -2.2987 2.999994)
			(end -2.500122 2.999994)
			(stroke
				(width 0.1524)
				(type default)
			)
			(layer "F.SilkS")
		)
		(fp_line
			(start 2.31394 -2.999994)
			(end 2.500122 -2.999994)
			(stroke
				(width 0.1524)
				(type default)
			)
			(layer "F.SilkS")
		)
		(fp_line
			(start 2.500122 -2.999994)
			(end 2.500122 -2.44348)
			(stroke
				(width 0.1524)
				(type default)
			)
			(layer "F.SilkS")
		)
		(fp_line
			(start 2.500122 2.339594)
			(end 2.500122 2.999994)
			(stroke
				(width 0.1524)
				(type default)
			)
			(layer "F.SilkS")
		)
		(fp_line
			(start 2.500122 2.999994)
			(end 2.2987 2.999994)
			(stroke
				(width 0.1524)
				(type default)
			)
			(layer "F.SilkS")
		)
		(fp_poly
			(pts
				(xy -2.758948 -2.432558) (xy -3.432556 -2.657094) (xy -2.983484 -3.105912)
			)
			(stroke
				(width 0)
				(type default)
			)
			(fill yes)
			(layer "F.SilkS")
		)
		(fp_line
			(start -2.500122 -2.999994)
			(end 2.500122 -2.999994)
			(stroke
				(width 0.1)
				(type default)
			)
			(layer "F.Fab")
		)
		(fp_line
			(start -2.500122 2.999994)
			(end -2.500122 -2.999994)
			(stroke
				(width 0.1)
				(type default)
			)
			(layer "F.Fab")
		)
		(fp_line
			(start 2.500122 -2.999994)
			(end 2.500122 2.999994)
			(stroke
				(width 0.1)
				(type default)
			)
			(layer "F.Fab")
		)
		(fp_line
			(start 2.500122 2.999994)
			(end -2.500122 2.999994)
			(stroke
				(width 0.1)
				(type default)
			)
			(layer "F.Fab")
		)
		(fp_poly
			(pts
				(xy -4.218432 -2.783078) (xy -4.218432 -1.767078) (xy -3.202432 -2.275078)
			)
			(stroke
				(width 0)
				(type default)
			)
			(fill yes)
			(layer "F.Fab")
		)
		(pad "1" smd rect
			(at -2.400046 -2.275078 90)
			(size 0.2286 0.6096)
			(layers "F.Cu" "F.Mask" "F.Paste")
			(net "PVDDIO_P1_VOS4")
		)
		(pad "2" smd rect
			(at -2.400046 -1.82499 90)
			(size 0.2286 0.6096)
			(layers "F.Cu" "F.Mask" "F.Paste")
			(net "GND")
		)
		(pad "3" smd rect
			(at -2.400046 -1.374902 90)
			(size 0.2286 0.6096)
			(layers "F.Cu" "F.Mask" "F.Paste")
			(net "PVDDIO_P1_VCC4")
		)
		(pad "4" smd rect
			(at -2.400046 -0.925068 90)
			(size 0.2286 0.6096)
			(layers "F.Cu" "F.Mask" "F.Paste")
			(net "PVDDCR_CPU1_P1_PVCC")
		)
		(pad "5" smd rect
			(at -2.400046 -0.47498 90)
			(size 0.2286 0.6096)
			(layers "F.Cu" "F.Mask" "F.Paste")
			(net "GND")
		)
		(pad "6" smd rect
			(at -2.400046 -0.024892 90)
			(size 0.2286 0.6096)
			(layers "F.Cu" "F.Mask" "F.Paste")
			(net "NC_PVDDIO_P1_GL1_4")
		)
		(pad "7_9-20_24" smd circle
			(at 0 1.150112 90)
			(size 0 0)
			(layers "F.Cu" "F.Mask" "F.Paste")
			(net "GND")
		)
		(pad "10_19" smd rect
			(at 0 2.899918 90)
			(size 0.6096 4.318)
			(layers "F.Cu" "F.Mask" "F.Paste")
			(net "SW_PVDDIO_P1_SW4")
		)
		(pad "25_29" smd rect
			(at 1.549908 -1.279906 270)
			(size 2.0574 2.3114)
			(layers "F.Cu" "F.Mask" "F.Paste")
			(net "SW_P12V_AUX_PVDDIO_P1_FLT")
		)
		(pad "30" smd rect
			(at 2.05994 -2.899918)
			(size 0.2286 0.6096)
			(layers "F.Cu" "F.Mask" "F.Paste")
			(net "SW_P12V_AUX_PVDDIO_P1_FLT")
		)
		(pad "31" smd rect
			(at 1.610106 -2.899918)
			(size 0.2286 0.6096)
			(layers "F.Cu" "F.Mask" "F.Paste")
			(net "NC_PVDDIO_P1_DNC4")
		)
		(pad "32" smd rect
			(at 1.160018 -2.899918)
			(size 0.2286 0.6096)
			(layers "F.Cu" "F.Mask" "F.Paste")
			(net "SW_PVDDIO_P1_BOOTR4")
		)
		(pad "33" smd rect
			(at 0.70993 -2.899918)
			(size 0.2286 0.6096)
			(layers "F.Cu" "F.Mask" "F.Paste")
			(net "SW_PVDDIO_P1_BOOT4")
		)
		(pad "34" smd rect
			(at 0.260096 -2.899918)
			(size 0.2286 0.6096)
			(layers "F.Cu" "F.Mask" "F.Paste")
			(net "PVDDIO_P1_PWM4")
		)
		(pad "35" smd rect
			(at -0.189992 -2.899918)
			(size 0.2286 0.6096)
			(layers "F.Cu" "F.Mask" "F.Paste")
			(net "PVDDIO_P1_VCC4")
		)
		(pad "36" smd rect
			(at -0.64008 -2.899918)
			(size 0.2286 0.6096)
			(layers "F.Cu" "F.Mask" "F.Paste")
			(net "PVDDIO_P1_TEMP1")
		)
		(pad "37" smd rect
			(at -1.089914 -2.899918)
			(size 0.2286 0.6096)
			(layers "F.Cu" "F.Mask" "F.Paste")
			(net "PVDDIO_P1_LSET4")
		)
		(pad "38" smd rect
			(at -1.540002 -2.899918)
			(size 0.2286 0.6096)
			(layers "F.Cu" "F.Mask" "F.Paste")
			(net "PVDDIO_P1_IMON4")
		)
		(pad "39" smd rect
			(at -1.99009 -2.899918)
			(size 0.2286 0.6096)
			(layers "F.Cu" "F.Mask" "F.Paste")
			(net "PVDDCR_CPU1_P1_VCCS")
		)
		(pad "40" smd rect
			(at -0.87503 -1.27508)
			(size 1.7526 1.9558)
			(layers "F.Cu" "F.Mask" "F.Paste")
			(net "GND")
		)
		(pad "41" smd rect
			(at -1.525016 0.249936 270)
			(size 0.3048 0.4572)
			(layers "F.Cu" "F.Mask" "F.Paste")
			(net "NC_PVDDIO_P1_GL2_4")
		)
		(zone
			(layer "F.Cu")
			(hatch none 0.5)
			(connect_pads
				(clearance 0)
			)
			(min_thickness 0.25)
			(keepout
				(tracks not_allowed)
				(vias allowed)
				(pads allowed)
				(copperpour not_allowed)
				(footprints allowed)
			)
			(placement
				(enabled no)
				(sheetname "")
			)
			(fill
				(thermal_gap 0.5)
				(thermal_bridge_width 0.5)
				(island_removal_mode 0)
			)
			(polygon
				(pts
					(xy 26.100532 -344.470482) (xy 31.100776 -344.470482) (xy 31.100776 -344.176858) (xy 26.100532 -344.176858)
				)
			)
		)
		(zone
			(layer "F.Cu")
			(hatch none 0.5)
			(connect_pads
				(clearance 0)
			)
			(min_thickness 0.25)
			(keepout
				(tracks not_allowed)
				(vias allowed)
				(pads allowed)
				(copperpour not_allowed)
				(footprints allowed)
			)
			(placement
				(enabled no)
				(sheetname "")
			)
			(fill
				(thermal_gap 0.5)
				(thermal_bridge_width 0.5)
				(island_removal_mode 0)
			)
			(polygon
				(pts
					(xy 26.556208 -348.381066) (xy 26.655014 -348.381066) (xy 26.798524 -348.237556) (xy 26.798524 -347.504512)
					(xy 26.655268 -347.361256) (xy 26.556208 -347.361256)
				)
			)
		)
	)
	(footprint ""
		(layer "F.Cu")
		(at 166.074344 -344.153998 -90)
		(property "Reference" "PR408"
			(at 0 0 270)
			(layer "F.SilkS")
			(hide yes)
			(effects
				(font
					(size 1.27 1.27)
				)
			)
		)
		(property "Value" ""
			(at 0 0 270)
			(layer "F.Fab")
			(effects
				(font
					(size 1.27 1.27)
				)
			)
		)
		(duplicate_pad_numbers_are_jumpers no)
		(fp_line
			(start -0.7874 0.4064)
			(end -0.7874 -0.4064)
			(stroke
				(width 0.1524)
				(type default)
			)
			(layer "F.SilkS")
		)
		(fp_line
			(start 0.7874 0.4064)
			(end -0.7874 0.4064)
			(stroke
				(width 0.1524)
				(type default)
			)
			(layer "F.SilkS")
		)
		(fp_line
			(start -0.7874 -0.4064)
			(end 0.7874 -0.4064)
			(stroke
				(width 0.1524)
				(type default)
			)
			(layer "F.SilkS")
		)
		(fp_line
			(start 0.7874 -0.4064)
			(end 0.7874 0.4064)
			(stroke
				(width 0.1524)
				(type default)
			)
			(layer "F.SilkS")
		)
		(fp_line
			(start -0.67945 0.3048)
			(end -0.67945 -0.305054)
			(stroke
				(width 0.1)
				(type default)
			)
			(layer "F.Fab")
		)
		(fp_line
			(start -0.12065 0.3048)
			(end -0.67945 0.3048)
			(stroke
				(width 0.1)
				(type default)
			)
			(layer "F.Fab")
		)
		(fp_line
			(start 0.120396 0.3048)
			(end 0.120396 0.2794)
			(stroke
				(width 0.1)
				(type default)
			)
			(layer "F.Fab")
		)
		(fp_line
			(start 0.67945 0.3048)
			(end 0.120396 0.3048)
			(stroke
				(width 0.1)
				(type default)
			)
			(layer "F.Fab")
		)
		(fp_line
			(start -0.12065 0.2794)
			(end -0.12065 0.3048)
			(stroke
				(width 0.1)
				(type default)
			)
			(layer "F.Fab")
		)
		(fp_line
			(start 0.120396 0.2794)
			(end -0.12065 0.2794)
			(stroke
				(width 0.1)
				(type default)
			)
			(layer "F.Fab")
		)
		(fp_line
			(start -0.12065 -0.2794)
			(end 0.12065 -0.2794)
			(stroke
				(width 0.1)
				(type default)
			)
			(layer "F.Fab")
		)
		(fp_line
			(start 0.12065 -0.2794)
			(end 0.12065 -0.3048)
			(stroke
				(width 0.1)
				(type default)
			)
			(layer "F.Fab")
		)
		(fp_line
			(start 0.12065 -0.3048)
			(end 0.67945 -0.3048)
			(stroke
				(width 0.1)
				(type default)
			)
			(layer "F.Fab")
		)
		(fp_line
			(start 0.67945 -0.3048)
			(end 0.67945 0.3048)
			(stroke
				(width 0.1)
				(type default)
			)
			(layer "F.Fab")
		)
		(fp_line
			(start -0.67945 -0.305054)
			(end -0.12065 -0.305054)
			(stroke
				(width 0.1)
				(type default)
			)
			(layer "F.Fab")
		)
		(fp_line
			(start -0.12065 -0.305054)
			(end -0.12065 -0.2794)
			(stroke
				(width 0.1)
				(type default)
			)
			(layer "F.Fab")
		)
		(pad "1" smd circle
			(at -0.40005 0 270)
			(size 0 0)
			(layers "F.Cu" "F.Mask" "F.Paste")
			(net "NC_PVDD11_S3_P1_IMON7")
		)
		(pad "2" smd circle
			(at 0.40005 0 270)
			(size 0 0)
			(layers "F.Cu" "F.Mask" "F.Paste")
			(net "GND")
		)
	)
	(footprint ""
		(layer "F.Cu")
		(at 72.463914 -144.881092)
		(property "Reference" "PR400"
			(at 0 0 0)
			(layer "F.SilkS")
			(hide yes)
			(effects
				(font
					(size 1.27 1.27)
				)
			)
		)
		(property "Value" ""
			(at 0 0 0)
			(layer "F.Fab")
			(effects
				(font
					(size 1.27 1.27)
				)
			)
		)
		(duplicate_pad_numbers_are_jumpers no)
		(fp_line
			(start -0.7874 -0.4064)
			(end 0.7874 -0.4064)
			(stroke
				(width 0.1524)
				(type default)
			)
			(layer "F.SilkS")
		)
		(fp_line
			(start -0.7874 0.4064)
			(end -0.7874 -0.4064)
			(stroke
				(width 0.1524)
				(type default)
			)
			(layer "F.SilkS")
		)
		(fp_line
			(start 0.7874 -0.4064)
			(end 0.7874 0.4064)
			(stroke
				(width 0.1524)
				(type default)
			)
			(layer "F.SilkS")
		)
		(fp_line
			(start 0.7874 0.4064)
			(end -0.7874 0.4064)
			(stroke
				(width 0.1524)
				(type default)
			)
			(layer "F.SilkS")
		)
		(fp_line
			(start -0.67945 -0.305054)
			(end -0.12065 -0.305054)
			(stroke
				(width 0.1)
				(type default)
			)
			(layer "F.Fab")
		)
		(fp_line
			(start -0.67945 0.3048)
			(end -0.67945 -0.305054)
			(stroke
				(width 0.1)
				(type default)
			)
			(layer "F.Fab")
		)
		(fp_line
			(start -0.12065 -0.305054)
			(end -0.12065 -0.2794)
			(stroke
				(width 0.1)
				(type default)
			)
			(layer "F.Fab")
		)
		(fp_line
			(start -0.12065 -0.2794)
			(end 0.12065 -0.2794)
			(stroke
				(width 0.1)
				(type default)
			)
			(layer "F.Fab")
		)
		(fp_line
			(start -0.12065 0.2794)
			(end -0.12065 0.3048)
			(stroke
				(width 0.1)
				(type default)
			)
			(layer "F.Fab")
		)
		(fp_line
			(start -0.12065 0.3048)
			(end -0.67945 0.3048)
			(stroke
				(width 0.1)
				(type default)
			)
			(layer "F.Fab")
		)
		(fp_line
			(start 0.120396 0.2794)
			(end -0.12065 0.2794)
			(stroke
				(width 0.1)
				(type default)
			)
			(layer "F.Fab")
		)
		(fp_line
			(start 0.120396 0.3048)
			(end 0.120396 0.2794)
			(stroke
				(width 0.1)
				(type default)
			)
			(layer "F.Fab")
		)
		(fp_line
			(start 0.12065 -0.3048)
			(end 0.67945 -0.3048)
			(stroke
				(width 0.1)
				(type default)
			)
			(layer "F.Fab")
		)
		(fp_line
			(start 0.12065 -0.2794)
			(end 0.12065 -0.3048)
			(stroke
				(width 0.1)
				(type default)
			)
			(layer "F.Fab")
		)
		(fp_line
			(start 0.67945 -0.3048)
			(end 0.67945 0.3048)
			(stroke
				(width 0.1)
				(type default)
			)
			(layer "F.Fab")
		)
		(fp_line
			(start 0.67945 0.3048)
			(end 0.120396 0.3048)
			(stroke
				(width 0.1)
				(type default)
			)
			(layer "F.Fab")
		)
		(pad "1" smd circle
			(at -0.40005 0)
			(size 0 0)
			(layers "F.Cu" "F.Mask" "F.Paste")
			(net "PVDD18_S5_P1_FB_RC")
		)
		(pad "2" smd circle
			(at 0.40005 0)
			(size 0 0)
			(layers "F.Cu" "F.Mask" "F.Paste")
			(net "VSENSE_PVDD18_S5_P1_DP")
		)
	)
	(footprint ""
		(layer "F.Cu")
		(at 50.072544 -41.99255 180)
		(property "Reference" "R1164"
			(at 0 0 180)
			(layer "F.SilkS")
			(hide yes)
			(effects
				(font
					(size 1.27 1.27)
				)
			)
		)
		(property "Value" ""
			(at 0 0 180)
			(layer "F.Fab")
			(effects
				(font
					(size 1.27 1.27)
				)
			)
		)
		(duplicate_pad_numbers_are_jumpers no)
		(fp_line
			(start 0.7874 0.4064)
			(end -0.7874 0.4064)
			(stroke
				(width 0.1524)
				(type default)
			)
			(layer "F.SilkS")
		)
		(fp_line
			(start 0.7874 -0.4064)
			(end 0.7874 0.4064)
			(stroke
				(width 0.1524)
				(type default)
			)
			(layer "F.SilkS")
		)
		(fp_line
			(start -0.7874 0.4064)
			(end -0.7874 -0.4064)
			(stroke
				(width 0.1524)
				(type default)
			)
			(layer "F.SilkS")
		)
		(fp_line
			(start -0.7874 -0.4064)
			(end 0.7874 -0.4064)
			(stroke
				(width 0.1524)
				(type default)
			)
			(layer "F.SilkS")
		)
		(fp_line
			(start 0.67945 0.3048)
			(end 0.120396 0.3048)
			(stroke
				(width 0.1)
				(type default)
			)
			(layer "F.Fab")
		)
		(fp_line
			(start 0.67945 -0.3048)
			(end 0.67945 0.3048)
			(stroke
				(width 0.1)
				(type default)
			)
			(layer "F.Fab")
		)
		(fp_line
			(start 0.12065 -0.2794)
			(end 0.12065 -0.3048)
			(stroke
				(width 0.1)
				(type default)
			)
			(layer "F.Fab")
		)
		(fp_line
			(start 0.12065 -0.3048)
			(end 0.67945 -0.3048)
			(stroke
				(width 0.1)
				(type default)
			)
			(layer "F.Fab")
		)
		(fp_line
			(start 0.120396 0.3048)
			(end 0.120396 0.2794)
			(stroke
				(width 0.1)
				(type default)
			)
			(layer "F.Fab")
		)
		(fp_line
			(start 0.120396 0.2794)
			(end -0.12065 0.2794)
			(stroke
				(width 0.1)
				(type default)
			)
			(layer "F.Fab")
		)
		(fp_line
			(start -0.12065 0.3048)
			(end -0.67945 0.3048)
			(stroke
				(width 0.1)
				(type default)
			)
			(layer "F.Fab")
		)
		(fp_line
			(start -0.12065 0.2794)
			(end -0.12065 0.3048)
			(stroke
				(width 0.1)
				(type default)
			)
			(layer "F.Fab")
		)
		(fp_line
			(start -0.12065 -0.2794)
			(end 0.12065 -0.2794)
			(stroke
				(width 0.1)
				(type default)
			)
			(layer "F.Fab")
		)
		(fp_line
			(start -0.12065 -0.305054)
			(end -0.12065 -0.2794)
			(stroke
				(width 0.1)
				(type default)
			)
			(layer "F.Fab")
		)
		(fp_line
			(start -0.67945 0.3048)
			(end -0.67945 -0.305054)
			(stroke
				(width 0.1)
				(type default)
			)
			(layer "F.Fab")
		)
		(fp_line
			(start -0.67945 -0.305054)
			(end -0.12065 -0.305054)
			(stroke
				(width 0.1)
				(type default)
			)
			(layer "F.Fab")
		)
		(pad "1" smd circle
			(at -0.40005 0 180)
			(size 0 0)
			(layers "F.Cu" "F.Mask" "F.Paste")
			(net "P12V_OCP_V3_2_EN_R")
		)
		(pad "2" smd circle
			(at 0.40005 0 180)
			(size 0 0)
			(layers "F.Cu" "F.Mask" "F.Paste")
			(net "P12V_OCP_V3_2_EN_R3")
		)
	)
	(footprint ""
		(layer "F.Cu")
		(at 319.940178 -43.700954)
		(property "Reference" "C2049"
			(at 0 0 0)
			(layer "F.SilkS")
			(hide yes)
			(effects
				(font
					(size 1.27 1.27)
				)
			)
		)
		(property "Value" ""
			(at 0 0 0)
			(layer "F.Fab")
			(effects
				(font
					(size 1.27 1.27)
				)
			)
		)
		(duplicate_pad_numbers_are_jumpers no)
		(fp_line
			(start -0.7874 -0.4064)
			(end 0.7874 -0.4064)
			(stroke
				(width 0.1524)
				(type default)
			)
			(layer "F.SilkS")
		)
		(fp_line
			(start -0.7874 0.4064)
			(end -0.7874 -0.4064)
			(stroke
				(width 0.1524)
				(type default)
			)
			(layer "F.SilkS")
		)
		(fp_line
			(start 0.7874 -0.4064)
			(end 0.7874 0.4064)
			(stroke
				(width 0.1524)
				(type default)
			)
			(layer "F.SilkS")
		)
		(fp_line
			(start 0.7874 0.4064)
			(end -0.7874 0.4064)
			(stroke
				(width 0.1524)
				(type default)
			)
			(layer "F.SilkS")
		)
		(fp_line
			(start -0.67945 -0.305054)
			(end -0.12065 -0.305054)
			(stroke
				(width 0.1)
				(type default)
			)
			(layer "F.Fab")
		)
		(fp_line
			(start -0.67945 0.3048)
			(end -0.67945 -0.305054)
			(stroke
				(width 0.1)
				(type default)
			)
			(layer "F.Fab")
		)
		(fp_line
			(start -0.12065 -0.305054)
			(end -0.12065 -0.2794)
			(stroke
				(width 0.1)
				(type default)
			)
			(layer "F.Fab")
		)
		(fp_line
			(start -0.12065 -0.2794)
			(end 0.12065 -0.2794)
			(stroke
				(width 0.1)
				(type default)
			)
			(layer "F.Fab")
		)
		(fp_line
			(start -0.12065 0.2794)
			(end -0.12065 0.3048)
			(stroke
				(width 0.1)
				(type default)
			)
			(layer "F.Fab")
		)
		(fp_line
			(start -0.12065 0.3048)
			(end -0.67945 0.3048)
			(stroke
				(width 0.1)
				(type default)
			)
			(layer "F.Fab")
		)
		(fp_line
			(start 0.120396 0.2794)
			(end -0.12065 0.2794)
			(stroke
				(width 0.1)
				(type default)
			)
			(layer "F.Fab")
		)
		(fp_line
			(start 0.120396 0.3048)
			(end 0.120396 0.2794)
			(stroke
				(width 0.1)
				(type default)
			)
			(layer "F.Fab")
		)
		(fp_line
			(start 0.12065 -0.3048)
			(end 0.67945 -0.3048)
			(stroke
				(width 0.1)
				(type default)
			)
			(layer "F.Fab")
		)
		(fp_line
			(start 0.12065 -0.2794)
			(end 0.12065 -0.3048)
			(stroke
				(width 0.1)
				(type default)
			)
			(layer "F.Fab")
		)
		(fp_line
			(start 0.67945 -0.3048)
			(end 0.67945 0.3048)
			(stroke
				(width 0.1)
				(type default)
			)
			(layer "F.Fab")
		)
		(fp_line
			(start 0.67945 0.3048)
			(end 0.120396 0.3048)
			(stroke
				(width 0.1)
				(type default)
			)
			(layer "F.Fab")
		)
		(pad "1" smd circle
			(at -0.40005 0)
			(size 0 0)
			(layers "F.Cu" "F.Mask" "F.Paste")
			(net "P5V_ADC_TIC")
		)
		(pad "2" smd circle
			(at 0.40005 0)
			(size 0 0)
			(layers "F.Cu" "F.Mask" "F.Paste")
			(net "GND")
		)
	)
)
